(kicad_pcb
	(version 20260206)
	(generator "pcbnew")
	(generator_version "10.0")
	(general
		(thickness 1.6)
		(legacy_teardrops no)
	)
	(paper "A4")
	(title_block
		(title "04192023_DAF0TMB3IC0_F0TG_MB_C_brd_V02_OCP.brd")
		(comment 1 "Grand Teton / footprints 3641-3645 of 8354")
	)
	(layers
		(0 "F.Cu" signal "TOP")
		(4 "In1.Cu" signal "GND")
		(6 "In2.Cu" signal "IN1")
		(8 "In3.Cu" signal "GND1")
		(10 "In4.Cu" signal "IN2")
		(12 "In5.Cu" signal "GND2")
		(14 "In6.Cu" signal "IN3")
		(16 "In7.Cu" signal "GND3")
		(18 "In8.Cu" signal "VCC")
		(20 "In9.Cu" signal "VCC1")
		(22 "In10.Cu" signal "GND4")
		(24 "In11.Cu" signal "IN4")
		(26 "In12.Cu" signal "GND5")
		(28 "In13.Cu" signal "IN5")
		(30 "In14.Cu" signal "GND6")
		(32 "In15.Cu" signal "IN6")
		(34 "In16.Cu" signal "GND7")
		(2 "B.Cu" signal "BOTTOM")
		(9 "F.Adhes" user "F.Adhesive")
		(11 "B.Adhes" user "B.Adhesive")
		(13 "F.Paste" user "Package Geometry/Pastemask Top")
		(15 "B.Paste" user "Package Geometry/Pastemask Bottom")
		(5 "F.SilkS" user "Ref Des/Silkscreen Top")
		(7 "B.SilkS" user "Ref Des/Silkscreen Bottom")
		(1 "F.Mask" user "Board Geometry/Soldermask Top")
		(3 "B.Mask" user "Board Geometry/Soldermask Bottom")
		(17 "Dwgs.User" user "User.Drawings")
		(19 "Cmts.User" user "User.Comments")
		(21 "Eco1.User" user "User.Eco1")
		(23 "Eco2.User" user "User.Eco2")
		(25 "Edge.Cuts" user "Board Geometry/Outline")
		(27 "Margin" user)
		(31 "F.CrtYd" user "Package Geometry/Place Bound Top")
		(29 "B.CrtYd" user "Package Geometry/Place Bound Bottom")
		(35 "F.Fab" user "Ref Des/Assembly Top")
		(33 "B.Fab" user "Ref Des/Assembly Bottom")
	)
	(footprint ""
		(layer "F.Cu")
		(at 235.89996 -81.700116 180)
		(property "Reference" "H115"
			(at -4.5466 -7.559548 180)
			(unlocked yes)
			(layer "B.SilkS")
			(effects
				(font
					(size 0.7874 0.5842)
					(thickness 0.1524)
				)
				(justify left mirror)
			)
		)
		(property "Value" ""
			(at 0 0 180)
			(layer "F.Fab")
			(effects
				(font
					(size 1.27 1.27)
				)
			)
		)
		(duplicate_pad_numbers_are_jumpers no)
		(fp_circle
			(center 0 0)
			(end -7.999984 0)
			(stroke
				(width 0.1524)
				(type default)
			)
			(fill no)
			(layer "F.SilkS")
		)
		(fp_circle
			(center 0 0)
			(end -7.999984 0)
			(stroke
				(width 0.1524)
				(type default)
			)
			(fill no)
			(layer "B.SilkS")
		)
		(fp_circle
			(center 0 0)
			(end -7.999984 0)
			(stroke
				(width 0.1)
				(type default)
			)
			(fill no)
			(layer "B.Fab")
		)
		(fp_circle
			(center 0 0)
			(end -7.999984 0)
			(stroke
				(width 0.1)
				(type default)
			)
			(fill no)
			(layer "F.Fab")
		)
		(pad "" np_thru_hole oval
			(at 0 0 90)
			(size 5.08 6.477)
			(drill oval 5.08 6.477)
			(layers "*.Cu" "*.Mask")
			(clearance 0.381)
			(thermal_gap 0.381)
		)
		(pad "2" thru_hole circle
			(at 4.38023 0 180)
			(size 0.9144 0.9144)
			(drill 0.5588)
			(layers "*.Cu" "*.Mask")
			(remove_unused_layers no)
			(net "GND")
			(clearance 0.0762)
			(thermal_gap 0.0762)
		)
		(pad "3" thru_hole circle
			(at 3.097276 -3.097276 180)
			(size 0.9144 0.9144)
			(drill 0.5588)
			(layers "*.Cu" "*.Mask")
			(remove_unused_layers no)
			(net "GND")
			(clearance 0.0762)
			(thermal_gap 0.0762)
		)
		(pad "4" thru_hole circle
			(at 0 -4.38023 180)
			(size 0.9144 0.9144)
			(drill 0.5588)
			(layers "*.Cu" "*.Mask")
			(remove_unused_layers no)
			(net "GND")
			(clearance 0.0762)
			(thermal_gap 0.0762)
		)
		(pad "5" thru_hole circle
			(at -3.097276 -3.097276 180)
			(size 0.9144 0.9144)
			(drill 0.5588)
			(layers "*.Cu" "*.Mask")
			(remove_unused_layers no)
			(net "GND")
			(clearance 0.0762)
			(thermal_gap 0.0762)
		)
		(pad "6" thru_hole circle
			(at -4.38023 0 180)
			(size 0.9144 0.9144)
			(drill 0.5588)
			(layers "*.Cu" "*.Mask")
			(remove_unused_layers no)
			(net "GND")
			(clearance 0.0762)
			(thermal_gap 0.0762)
		)
		(pad "7" thru_hole circle
			(at -3.097276 3.097276 180)
			(size 0.9144 0.9144)
			(drill 0.5588)
			(layers "*.Cu" "*.Mask")
			(remove_unused_layers no)
			(net "GND")
			(clearance 0.0762)
			(thermal_gap 0.0762)
		)
		(pad "8" thru_hole circle
			(at 0 4.38023 180)
			(size 0.9144 0.9144)
			(drill 0.5588)
			(layers "*.Cu" "*.Mask")
			(remove_unused_layers no)
			(net "GND")
			(clearance 0.0762)
			(thermal_gap 0.0762)
		)
		(pad "9" thru_hole circle
			(at 3.097276 3.097276 180)
			(size 0.9144 0.9144)
			(drill 0.5588)
			(layers "*.Cu" "*.Mask")
			(remove_unused_layers no)
			(net "GND")
			(clearance 0.0762)
			(thermal_gap 0.0762)
		)
		(zone
			(layer "F.Cu")
			(hatch none 0.5)
			(connect_pads
				(clearance 0)
			)
			(min_thickness 0.25)
			(keepout
				(tracks not_allowed)
				(vias allowed)
				(pads allowed)
				(copperpour not_allowed)
				(footprints allowed)
			)
			(placement
				(enabled no)
				(sheetname "")
			)
			(fill
				(thermal_gap 0.5)
				(thermal_bridge_width 0.5)
				(island_removal_mode 0)
			)
			(polygon
				(pts
					(arc
						(start 230.39197 -81.700116)
						(mid 232.005223 -85.594853)
						(end 235.89996 -87.208106)
					)
					(arc
						(start 235.89996 -86.725506)
						(mid 230.87457 -81.700116)
						(end 235.89996 -76.674726)
					)
					(arc
						(start 235.89996 -76.192126)
						(mid 232.005223 -77.805379)
						(end 230.39197 -81.700116)
					)
				)
			)
		)
		(zone
			(layer "F.Cu")
			(hatch none 0.5)
			(connect_pads
				(clearance 0)
			)
			(min_thickness 0.25)
			(keepout
				(tracks not_allowed)
				(vias allowed)
				(pads allowed)
				(copperpour not_allowed)
				(footprints allowed)
			)
			(placement
				(enabled no)
				(sheetname "")
			)
			(fill
				(thermal_gap 0.5)
				(thermal_bridge_width 0.5)
				(island_removal_mode 0)
			)
			(polygon
				(pts
					(arc
						(start 241.40795 -81.700116)
						(mid 239.794697 -85.594853)
						(end 235.89996 -87.208106)
					)
					(arc
						(start 235.89996 -86.725506)
						(mid 240.92535 -81.700116)
						(end 235.89996 -76.674726)
					)
					(arc
						(start 235.89996 -76.192126)
						(mid 239.794697 -77.805379)
						(end 241.40795 -81.700116)
					)
				)
			)
		)
		(zone
			(layers "F.Cu" "B.Cu" "In1.Cu" "In2.Cu" "In3.Cu" "In4.Cu" "In5.Cu" "In6.Cu"
				"In7.Cu" "In8.Cu" "In9.Cu" "In10.Cu" "In11.Cu" "In12.Cu" "In13.Cu" "In14.Cu"
				"In15.Cu" "In16.Cu"
			)
			(hatch none 0.5)
			(connect_pads
				(clearance 0)
			)
			(min_thickness 0.25)
			(keepout
				(tracks not_allowed)
				(vias allowed)
				(pads allowed)
				(copperpour not_allowed)
				(footprints allowed)
			)
			(placement
				(enabled no)
				(sheetname "")
			)
			(fill
				(thermal_gap 0.5)
				(thermal_bridge_width 0.5)
				(island_removal_mode 0)
			)
			(polygon
				(pts
					(arc
						(start 233.71556 -78.64221)
						(mid 235.89996 -85.458093)
						(end 238.08436 -78.64221)
					)
				)
			)
		)
		(zone
			(layer "B.Cu")
			(hatch none 0.5)
			(connect_pads
				(clearance 0)
			)
			(min_thickness 0.25)
			(keepout
				(tracks not_allowed)
				(vias allowed)
				(pads allowed)
				(copperpour not_allowed)
				(footprints allowed)
			)
			(placement
				(enabled no)
				(sheetname "")
			)
			(fill
				(thermal_gap 0.5)
				(thermal_bridge_width 0.5)
				(island_removal_mode 0)
			)
			(polygon
				(pts
					(arc
						(start 235.89996 -89.7001)
						(mid 227.899976 -81.700116)
						(end 235.89996 -73.700132)
					)
					(arc
						(start 235.89996 -76.446126)
						(mid 232.184828 -77.984984)
						(end 230.64597 -81.700116)
					)
					(arc
						(start 230.64597 -81.700116)
						(mid 232.184828 -85.415248)
						(end 235.89996 -86.954106)
					)
				)
			)
		)
		(zone
			(layer "B.Cu")
			(hatch none 0.5)
			(connect_pads
				(clearance 0)
			)
			(min_thickness 0.25)
			(keepout
				(tracks not_allowed)
				(vias allowed)
				(pads allowed)
				(copperpour not_allowed)
				(footprints allowed)
			)
			(placement
				(enabled no)
				(sheetname "")
			)
			(fill
				(thermal_gap 0.5)
				(thermal_bridge_width 0.5)
				(island_removal_mode 0)
			)
			(polygon
				(pts
					(arc
						(start 235.89996 -89.7001)
						(mid 243.899944 -81.700116)
						(end 235.89996 -73.700132)
					)
					(arc
						(start 235.89996 -76.446126)
						(mid 239.615092 -77.984984)
						(end 241.15395 -81.700116)
					)
					(arc
						(start 241.15395 -81.700116)
						(mid 239.615092 -85.415248)
						(end 235.89996 -86.954106)
					)
				)
			)
		)
	)
	(footprint ""
		(layer "F.Cu")
		(at 360.710226 -62.0903 180)
		(property "Reference" "D8000"
			(at 4.256532 1.652524 0)
			(unlocked yes)
			(layer "F.SilkS")
			(effects
				(font
					(size 0.7874 0.5842)
					(thickness 0.1524)
				)
				(justify left)
			)
		)
		(property "Value" ""
			(at 0 0 180)
			(layer "F.Fab")
			(effects
				(font
					(size 1.27 1.27)
				)
			)
		)
		(duplicate_pad_numbers_are_jumpers no)
		(fp_line
			(start 1.16078 0.4826)
			(end -0.64008 0.4826)
			(stroke
				(width 0.1524)
				(type default)
			)
			(layer "F.SilkS")
		)
		(fp_line
			(start 1.16078 -0.4826)
			(end 1.16078 0.4826)
			(stroke
				(width 0.1524)
				(type default)
			)
			(layer "F.SilkS")
		)
		(fp_line
			(start 1.03378 0.4826)
			(end -0.79248 0.4826)
			(stroke
				(width 0.1524)
				(type default)
			)
			(layer "F.SilkS")
		)
		(fp_line
			(start 1.03378 -0.4826)
			(end 1.03378 0.4826)
			(stroke
				(width 0.1524)
				(type default)
			)
			(layer "F.SilkS")
		)
		(fp_line
			(start 0.90678 0.4826)
			(end -0.90678 0.4826)
			(stroke
				(width 0.1524)
				(type default)
			)
			(layer "F.SilkS")
		)
		(fp_line
			(start 0.90678 -0.4826)
			(end 0.90678 0.4826)
			(stroke
				(width 0.1524)
				(type default)
			)
			(layer "F.SilkS")
		)
		(fp_line
			(start -0.64008 -0.4826)
			(end 1.16078 -0.4826)
			(stroke
				(width 0.1524)
				(type default)
			)
			(layer "F.SilkS")
		)
		(fp_line
			(start -0.79248 -0.4826)
			(end 1.03378 -0.4826)
			(stroke
				(width 0.1524)
				(type default)
			)
			(layer "F.SilkS")
		)
		(fp_line
			(start -0.89408 -0.4826)
			(end 0.90678 -0.4826)
			(stroke
				(width 0.1524)
				(type default)
			)
			(layer "F.SilkS")
		)
		(fp_line
			(start -0.90678 0.4826)
			(end -0.90678 -0.4699)
			(stroke
				(width 0.1524)
				(type default)
			)
			(layer "F.SilkS")
		)
		(fp_line
			(start 0.499872 0.249936)
			(end -0.499872 0.249936)
			(stroke
				(width 0.1)
				(type default)
			)
			(layer "F.Fab")
		)
		(fp_line
			(start 0.499872 -0.249936)
			(end 0.499872 0.249936)
			(stroke
				(width 0.1)
				(type default)
			)
			(layer "F.Fab")
		)
		(fp_line
			(start -0.499872 0.249936)
			(end -0.499872 -0.249936)
			(stroke
				(width 0.1)
				(type default)
			)
			(layer "F.Fab")
		)
		(fp_line
			(start -0.499872 -0.249936)
			(end 0.499872 -0.249936)
			(stroke
				(width 0.1)
				(type default)
			)
			(layer "F.Fab")
		)
		(pad "A" smd rect
			(at -0.47498 0 180)
			(size 0.6096 0.7112)
			(layers "F.Cu" "F.Mask" "F.Paste")
			(net "LED_P12V_AUX_R1")
		)
		(pad "C" smd rect
			(at 0.47498 0 180)
			(size 0.6096 0.7112)
			(layers "F.Cu" "F.Mask" "F.Paste")
			(net "GND")
		)
	)
	(footprint ""
		(layer "F.Cu")
		(at 432.12639 -50.447448 180)
		(property "Reference" "PC3"
			(at -2.5908 -1.793748 0)
			(unlocked yes)
			(layer "F.SilkS")
			(effects
				(font
					(size 0.7874 0.5842)
					(thickness 0.1524)
				)
				(justify left)
			)
		)
		(property "Value" ""
			(at 0 0 180)
			(layer "F.Fab")
			(effects
				(font
					(size 1.27 1.27)
				)
			)
		)
		(duplicate_pad_numbers_are_jumpers no)
		(fp_line
			(start -3.400044 1.249934)
			(end 3.400044 1.249934)
			(stroke
				(width 0.1524)
				(type default)
			)
			(layer "F.SilkS")
		)
		(fp_circle
			(center 0 1.249934)
			(end -3.39979 1.249934)
			(stroke
				(width 0.1524)
				(type default)
			)
			(fill no)
			(layer "F.SilkS")
		)
		(fp_poly
			(pts
				(arc
					(start 3.400044 1.249934)
					(mid 0 4.649978)
					(end -3.400044 1.249934)
				)
			)
			(stroke
				(width 0)
				(type default)
			)
			(fill yes)
			(layer "F.SilkS")
		)
		(fp_circle
			(center 0 1.249934)
			(end -3.39979 1.249934)
			(stroke
				(width 0.1)
				(type default)
			)
			(fill no)
			(layer "F.Fab")
		)
		(pad "1" thru_hole rect
			(at 0 0 180)
			(size 1.524 1.524)
			(drill 1.016)
			(layers "*.Cu" "*.Mask")
			(remove_unused_layers no)
			(net "SW_P3V3_AUX_FLT")
			(clearance 0)
			(padstack
				(mode front_inner_back)
				(layer "Inner"
					(shape circle)
					(size 1.524 1.524)
					(clearance 0)
				)
				(layer "B.Cu"
					(shape rect)
					(size 1.524 1.524)
					(clearance 0)
				)
			)
		)
		(pad "2" thru_hole circle
			(at 0 2.500122 180)
			(size 1.524 1.524)
			(drill 1.016)
			(layers "*.Cu" "*.Mask")
			(remove_unused_layers no)
			(net "GND")
			(clearance 0)
		)
	)
	(footprint ""
		(layer "F.Cu")
		(at 440.807602 -429.37811 -90)
		(property "Reference" "R649"
			(at 0 0 270)
			(layer "F.SilkS")
			(hide yes)
			(effects
				(font
					(size 1.27 1.27)
				)
			)
		)
		(property "Value" ""
			(at 0 0 270)
			(layer "F.Fab")
			(effects
				(font
					(size 1.27 1.27)
				)
			)
		)
		(duplicate_pad_numbers_are_jumpers no)
		(fp_line
			(start -0.7874 0.4064)
			(end -0.7874 -0.4064)
			(stroke
				(width 0.1524)
				(type default)
			)
			(layer "F.SilkS")
		)
		(fp_line
			(start 0.7874 0.4064)
			(end -0.7874 0.4064)
			(stroke
				(width 0.1524)
				(type default)
			)
			(layer "F.SilkS")
		)
		(fp_line
			(start -0.7874 -0.4064)
			(end 0.7874 -0.4064)
			(stroke
				(width 0.1524)
				(type default)
			)
			(layer "F.SilkS")
		)
		(fp_line
			(start 0.7874 -0.4064)
			(end 0.7874 0.4064)
			(stroke
				(width 0.1524)
				(type default)
			)
			(layer "F.SilkS")
		)
		(fp_line
			(start -0.67945 0.3048)
			(end -0.67945 -0.305054)
			(stroke
				(width 0.1)
				(type default)
			)
			(layer "F.Fab")
		)
		(fp_line
			(start -0.12065 0.3048)
			(end -0.67945 0.3048)
			(stroke
				(width 0.1)
				(type default)
			)
			(layer "F.Fab")
		)
		(fp_line
			(start 0.120396 0.3048)
			(end 0.120396 0.2794)
			(stroke
				(width 0.1)
				(type default)
			)
			(layer "F.Fab")
		)
		(fp_line
			(start 0.67945 0.3048)
			(end 0.120396 0.3048)
			(stroke
				(width 0.1)
				(type default)
			)
			(layer "F.Fab")
		)
		(fp_line
			(start -0.12065 0.2794)
			(end -0.12065 0.3048)
			(stroke
				(width 0.1)
				(type default)
			)
			(layer "F.Fab")
		)
		(fp_line
			(start 0.120396 0.2794)
			(end -0.12065 0.2794)
			(stroke
				(width 0.1)
				(type default)
			)
			(layer "F.Fab")
		)
		(fp_line
			(start -0.12065 -0.2794)
			(end 0.12065 -0.2794)
			(stroke
				(width 0.1)
				(type default)
			)
			(layer "F.Fab")
		)
		(fp_line
			(start 0.12065 -0.2794)
			(end 0.12065 -0.3048)
			(stroke
				(width 0.1)
				(type default)
			)
			(layer "F.Fab")
		)
		(fp_line
			(start 0.12065 -0.3048)
			(end 0.67945 -0.3048)
			(stroke
				(width 0.1)
				(type default)
			)
			(layer "F.Fab")
		)
		(fp_line
			(start 0.67945 -0.3048)
			(end 0.67945 0.3048)
			(stroke
				(width 0.1)
				(type default)
			)
			(layer "F.Fab")
		)
		(fp_line
			(start -0.67945 -0.305054)
			(end -0.12065 -0.305054)
			(stroke
				(width 0.1)
				(type default)
			)
			(layer "F.Fab")
		)
		(fp_line
			(start -0.12065 -0.305054)
			(end -0.12065 -0.2794)
			(stroke
				(width 0.1)
				(type default)
			)
			(layer "F.Fab")
		)
		(pad "1" smd circle
			(at -0.40005 0 270)
			(size 0 0)
			(layers "F.Cu" "F.Mask" "F.Paste")
			(net "P3V3_AUX")
		)
		(pad "2" smd circle
			(at 0.40005 0 270)
			(size 0 0)
			(layers "F.Cu" "F.Mask" "F.Paste")
			(net "TP_P0V9_RETIMER_CPU0_PMALERT")
		)
	)
	(footprint ""
		(layer "F.Cu")
		(at 78.867 -66.802 180)
		(property "Reference" "R8096"
			(at 0 0 180)
			(layer "F.SilkS")
			(hide yes)
			(effects
				(font
					(size 1.27 1.27)
				)
			)
		)
		(property "Value" ""
			(at 0 0 180)
			(layer "F.Fab")
			(effects
				(font
					(size 1.27 1.27)
				)
			)
		)
		(duplicate_pad_numbers_are_jumpers no)
		(fp_line
			(start 0.7874 0.4064)
			(end -0.7874 0.4064)
			(stroke
				(width 0.1524)
				(type default)
			)
			(layer "F.SilkS")
		)
		(fp_line
			(start 0.7874 -0.4064)
			(end 0.7874 0.4064)
			(stroke
				(width 0.1524)
				(type default)
			)
			(layer "F.SilkS")
		)
		(fp_line
			(start -0.7874 0.4064)
			(end -0.7874 -0.4064)
			(stroke
				(width 0.1524)
				(type default)
			)
			(layer "F.SilkS")
		)
		(fp_line
			(start -0.7874 -0.4064)
			(end 0.7874 -0.4064)
			(stroke
				(width 0.1524)
				(type default)
			)
			(layer "F.SilkS")
		)
		(fp_line
			(start 0.67945 0.3048)
			(end 0.120396 0.3048)
			(stroke
				(width 0.1)
				(type default)
			)
			(layer "F.Fab")
		)
		(fp_line
			(start 0.67945 -0.3048)
			(end 0.67945 0.3048)
			(stroke
				(width 0.1)
				(type default)
			)
			(layer "F.Fab")
		)
		(fp_line
			(start 0.12065 -0.2794)
			(end 0.12065 -0.3048)
			(stroke
				(width 0.1)
				(type default)
			)
			(layer "F.Fab")
		)
		(fp_line
			(start 0.12065 -0.3048)
			(end 0.67945 -0.3048)
			(stroke
				(width 0.1)
				(type default)
			)
			(layer "F.Fab")
		)
		(fp_line
			(start 0.120396 0.3048)
			(end 0.120396 0.2794)
			(stroke
				(width 0.1)
				(type default)
			)
			(layer "F.Fab")
		)
		(fp_line
			(start 0.120396 0.2794)
			(end -0.12065 0.2794)
			(stroke
				(width 0.1)
				(type default)
			)
			(layer "F.Fab")
		)
		(fp_line
			(start -0.12065 0.3048)
			(end -0.67945 0.3048)
			(stroke
				(width 0.1)
				(type default)
			)
			(layer "F.Fab")
		)
		(fp_line
			(start -0.12065 0.2794)
			(end -0.12065 0.3048)
			(stroke
				(width 0.1)
				(type default)
			)
			(layer "F.Fab")
		)
		(fp_line
			(start -0.12065 -0.2794)
			(end 0.12065 -0.2794)
			(stroke
				(width 0.1)
				(type default)
			)
			(layer "F.Fab")
		)
		(fp_line
			(start -0.12065 -0.305054)
			(end -0.12065 -0.2794)
			(stroke
				(width 0.1)
				(type default)
			)
			(layer "F.Fab")
		)
		(fp_line
			(start -0.67945 0.3048)
			(end -0.67945 -0.305054)
			(stroke
				(width 0.1)
				(type default)
			)
			(layer "F.Fab")
		)
		(fp_line
			(start -0.67945 -0.305054)
			(end -0.12065 -0.305054)
			(stroke
				(width 0.1)
				(type default)
			)
			(layer "F.Fab")
		)
		(pad "1" smd circle
			(at -0.40005 0 180)
			(size 0 0)
			(layers "F.Cu" "F.Mask" "F.Paste")
			(net "OCP_V3_2_P3V3_R1_PWRGD")
		)
		(pad "2" smd circle
			(at 0.40005 0 180)
			(size 0 0)
			(layers "F.Cu" "F.Mask" "F.Paste")
			(net "GND")
		)
	)
)
